(kicad_pcb
	(version 20241229)
	(generator "pcbnew")
	(generator_version "9.0")
	(general
		(thickness 1.599998)
		(legacy_teardrops no)
	)
	(paper "A4")
	(title_block
		(date "2023-02-12")
		(rev "1.1.5")
		(comment 9 "footprints 101-105 of 473")
	)
	(layers
		(0 "F.Cu" signal)
		(4 "In1.Cu" power "In1.GND")
		(6 "In2.Cu" signal)
		(8 "In3.Cu" power "In3.GND")
		(10 "In4.Cu" power "In4.VCC")
		(12 "In5.Cu" signal)
		(14 "In6.Cu" power "In6.VCC")
		(2 "B.Cu" signal)
		(9 "F.Adhes" user "F.Adhesive")
		(11 "B.Adhes" user "B.Adhesive")
		(13 "F.Paste" user)
		(15 "B.Paste" user)
		(5 "F.SilkS" user "F.Silkscreen")
		(7 "B.SilkS" user "B.Silkscreen")
		(1 "F.Mask" user)
		(3 "B.Mask" user)
		(17 "Dwgs.User" user "User.Drawings")
		(19 "Cmts.User" user "User.Comments")
		(21 "Eco1.User" user "User.Eco1")
		(23 "Eco2.User" user "User.Eco2")
		(25 "Edge.Cuts" user)
		(27 "Margin" user)
		(31 "F.CrtYd" user "F.Courtyard")
		(29 "B.CrtYd" user "B.Courtyard")
		(35 "F.Fab" user)
		(33 "B.Fab" user)
	)
	(footprint "antmicro-footprints:R-PDSO-N15"
		(layer "F.Cu")
		(at 156.86 119.629 -90)
		(property "Reference" "IC1"
			(at 0.271 -4.14 270)
			(layer "F.SilkS")
			(effects
				(font
					(size 0.7 0.7)
					(thickness 0.15)
				)
				(justify left bottom)
			)
		)
		(property "Value" "TPD8S009DSMR"
			(at 0 4.4 270)
			(layer "F.Fab")
			(effects
				(font
					(size 0.7 0.7)
					(thickness 0.15)
				)
				(justify left bottom)
			)
		)
		(property "Author" "Antmicro"
			(at 37.231 276.489 0)
			(layer "F.Fab")
			(hide yes)
			(effects
				(font
					(size 1 1)
					(thickness 0.15)
				)
			)
		)
		(property "License" "Apache-2.0"
			(at 37.231 276.489 0)
			(layer "F.Fab")
			(hide yes)
			(effects
				(font
					(size 1 1)
					(thickness 0.15)
				)
			)
		)
		(property "MPN" "TPD8S009DSMR"
			(at 37.231 276.489 0)
			(layer "F.Fab")
			(hide yes)
			(effects
				(font
					(size 1 1)
					(thickness 0.15)
				)
			)
		)
		(property "Manufacturer" "Texas Instruments"
			(at 37.231 276.489 0)
			(layer "F.Fab")
			(hide yes)
			(effects
				(font
					(size 1 1)
					(thickness 0.15)
				)
			)
		)
		(sheetname "Interfaces")
		(sheetfile "interfaces.kicad_sch")
		(attr smd)
		(fp_circle
			(center -1.6 -3.2)
			(end -1.6 -3.15)
			(stroke
				(width 0.15)
				(type solid)
			)
			(fill yes)
			(layer "F.SilkS")
		)
		(fp_rect
			(start 1.8 -3.5)
			(end -1.89 3.49)
			(stroke
				(width 0.05)
				(type solid)
			)
			(fill no)
			(layer "F.CrtYd")
		)
		(fp_line
			(start -1.3 -3.051)
			(end -1.1 -3.25)
			(stroke
				(width 0.15)
				(type solid)
			)
			(layer "F.Fab")
		)
		(fp_rect
			(start 1.301 -3.25)
			(end -1.3 3.249)
			(stroke
				(width 0.15)
				(type solid)
			)
			(fill no)
			(layer "F.Fab")
		)
		(pad "1" smd roundrect
			(at -0.95 -2.75 180)
			(size 0.3 1.45)
			(layers "F.Cu" "F.Mask" "F.Paste")
			(roundrect_rratio 0.25)
			(net 670 "/Interfaces/C_TMDS_D2_P")
			(pinfunction "D0+")
			(pintype "passive")
		)
		(pad "2" smd roundrect
			(at -0.95 -2.25 180)
			(size 0.3 1.45)
			(layers "F.Cu" "F.Mask" "F.Paste")
			(roundrect_rratio 0.25)
			(net 5 "GND")
			(pinfunction "GND")
			(pintype "passive")
		)
		(pad "3" smd roundrect
			(at -0.95 -1.75 180)
			(size 0.3 1.45)
			(layers "F.Cu" "F.Mask" "F.Paste")
			(roundrect_rratio 0.25)
			(net 669 "/Interfaces/C_TMDS_D2_N")
			(pinfunction "D0-")
			(pintype "passive")
		)
		(pad "4" smd roundrect
			(at -0.95 -1.25 180)
			(size 0.3 1.45)
			(layers "F.Cu" "F.Mask" "F.Paste")
			(roundrect_rratio 0.25)
			(net 668 "/Interfaces/C_TMDS_D1_P")
			(pinfunction "D1+")
			(pintype "passive")
		)
		(pad "5" smd roundrect
			(at -0.95 -0.75 180)
			(size 0.3 1.45)
			(layers "F.Cu" "F.Mask" "F.Paste")
			(roundrect_rratio 0.25)
			(net 5 "GND")
			(pinfunction "GND")
			(pintype "passive")
		)
		(pad "6" smd roundrect
			(at -0.95 -0.25 180)
			(size 0.3 1.45)
			(layers "F.Cu" "F.Mask" "F.Paste")
			(roundrect_rratio 0.25)
			(net 667 "/Interfaces/C_TMDS_D1_N")
			(pinfunction "D1-")
			(pintype "passive")
		)
		(pad "7" smd roundrect
			(at -0.95 0.247 180)
			(size 0.3 1.45)
			(layers "F.Cu" "F.Mask" "F.Paste")
			(roundrect_rratio 0.25)
			(net 666 "/Interfaces/C_TMDS_D0_P")
			(pinfunction "D2+")
			(pintype "passive")
		)
		(pad "8" smd roundrect
			(at -0.95 0.747 180)
			(size 0.3 1.45)
			(layers "F.Cu" "F.Mask" "F.Paste")
			(roundrect_rratio 0.25)
			(net 5 "GND")
			(pinfunction "GND")
			(pintype "passive")
		)
		(pad "9" smd roundrect
			(at -0.95 1.249 180)
			(size 0.3 1.45)
			(layers "F.Cu" "F.Mask" "F.Paste")
			(roundrect_rratio 0.25)
			(net 665 "/Interfaces/C_TMDS_D0_N")
			(pinfunction "D2-")
			(pintype "passive")
		)
		(pad "10" smd roundrect
			(at -0.95 1.749 180)
			(size 0.3 1.45)
			(layers "F.Cu" "F.Mask" "F.Paste")
			(roundrect_rratio 0.25)
			(net 664 "/Interfaces/C_TMDS_CLK_P")
			(pinfunction "D3+")
			(pintype "passive")
		)
		(pad "11" smd roundrect
			(at -0.95 2.249 180)
			(size 0.3 1.45)
			(layers "F.Cu" "F.Mask" "F.Paste")
			(roundrect_rratio 0.25)
			(net 5 "GND")
			(pinfunction "GND")
			(pintype "passive")
		)
		(pad "12" smd roundrect
			(at -0.95 2.749 180)
			(size 0.3 1.45)
			(layers "F.Cu" "F.Mask" "F.Paste")
			(roundrect_rratio 0.25)
			(net 663 "/Interfaces/C_TMDS_CLK_N")
			(pinfunction "D3-")
			(pintype "passive")
		)
		(pad "13" smd roundrect
			(at 0.901 1.499 180)
			(size 0.3 1.45)
			(layers "F.Cu" "F.Mask" "F.Paste")
			(roundrect_rratio 0.25)
			(net 459 "3V3_SYS")
			(pinfunction "VCC")
			(pintype "power_in")
		)
		(pad "14" smd roundrect
			(at 0.901 0 180)
			(size 0.3 1.45)
			(layers "F.Cu" "F.Mask" "F.Paste")
			(roundrect_rratio 0.25)
			(net 75 "unconnected-(IC1-NC-Pad14)")
			(pinfunction "NC")
			(pintype "no_connect")
		)
		(pad "15" smd roundrect
			(at 0.901 -1.5 180)
			(size 0.3 1.45)
			(layers "F.Cu" "F.Mask" "F.Paste")
			(roundrect_rratio 0.25)
			(net 459 "3V3_SYS")
			(pinfunction "VCC")
			(pintype "passive")
		)
	)
	(footprint "antmicro-footprints:R_0402_1005Metric"
		(layer "F.Cu")
		(at 159.659 115.477 -90)
		(descr "Resistor SMD 0402")
		(tags "resistor SMD 0402")
		(property "Reference" "R46"
			(at 1.25 -2.341 270)
			(layer "F.SilkS")
			(effects
				(font
					(size 0.7 0.7)
					(thickness 0.15)
				)
				(justify left bottom)
			)
		)
		(property "Value" "R_0R_0402"
			(at 0 1.4 270)
			(layer "F.Fab")
			(effects
				(font
					(size 0.7 0.7)
					(thickness 0.15)
				)
				(justify left bottom)
			)
		)
		(property "Description" "0R resistor in 0402 package with unspecified tolerance"
			(at 0 0 270)
			(layer "F.Fab")
			(hide yes)
			(effects
				(font
					(size 1.27 1.27)
					(thickness 0.15)
				)
			)
		)
		(property "Author" "Antmicro"
			(at 44.182 275.136 0)
			(layer "F.Fab")
			(hide yes)
			(effects
				(font
					(size 1 1)
					(thickness 0.15)
				)
			)
		)
		(property "Current" "1A"
			(at 44.182 275.136 0)
			(layer "F.Fab")
			(hide yes)
			(effects
				(font
					(size 1 1)
					(thickness 0.15)
				)
			)
		)
		(property "License" "Apache-2.0"
			(at 44.182 275.136 0)
			(layer "F.Fab")
			(hide yes)
			(effects
				(font
					(size 1 1)
					(thickness 0.15)
				)
			)
		)
		(property "MPN" "ERJ2GE0R00X"
			(at 44.182 275.136 0)
			(layer "F.Fab")
			(hide yes)
			(effects
				(font
					(size 1 1)
					(thickness 0.15)
				)
			)
		)
		(property "Manufacturer" "Panasonic"
			(at 44.182 275.136 0)
			(layer "F.Fab")
			(hide yes)
			(effects
				(font
					(size 1 1)
					(thickness 0.15)
				)
			)
		)
		(property "Tolerance" ""
			(at 44.182 275.136 0)
			(layer "F.Fab")
			(hide yes)
			(effects
				(font
					(size 1 1)
					(thickness 0.15)
				)
			)
		)
		(property "Val" "0R"
			(at 44.182 275.136 0)
			(layer "F.Fab")
			(hide yes)
			(effects
				(font
					(size 1 1)
					(thickness 0.15)
				)
			)
		)
		(sheetname "Interfaces")
		(sheetfile "interfaces.kicad_sch")
		(attr smd)
		(fp_rect
			(start -0.93 -0.47)
			(end 0.93 0.47)
			(stroke
				(width 0.05)
				(type solid)
			)
			(fill no)
			(layer "F.CrtYd")
		)
		(fp_rect
			(start -0.5 -0.25)
			(end 0.5 0.25)
			(stroke
				(width 0.15)
				(type solid)
			)
			(fill no)
			(layer "F.Fab")
		)
		(pad "1" smd roundrect
			(at -0.485 0 270)
			(size 0.59 0.64)
			(layers "F.Cu" "F.Mask" "F.Paste")
			(roundrect_rratio 0.25)
			(net 50 "TMDS_D2_P")
			(pintype "passive")
		)
		(pad "2" smd roundrect
			(at 0.485 0 270)
			(size 0.59 0.64)
			(layers "F.Cu" "F.Mask" "F.Paste")
			(roundrect_rratio 0.25)
			(net 670 "/Interfaces/C_TMDS_D2_P")
			(pintype "passive")
		)
	)
	(footprint "antmicro-footprints:C_Pol_EIA-D"
		(layer "F.Cu")
		(at 150.4564 87.3496 180)
		(descr "Capacitor SMD KEMET_D")
		(tags "capacitor SMD KEMET_D")
		(property "Reference" "C81"
			(at -1.7436 -3.1504 180)
			(layer "F.SilkS")
			(effects
				(font
					(size 0.7 0.7)
					(thickness 0.15)
				)
				(justify left bottom)
			)
		)
		(property "Value" "C_330u_KEMET_D"
			(at 0 3.4 180)
			(layer "F.Fab")
			(effects
				(font
					(size 0.7 0.7)
					(thickness 0.15)
				)
				(justify left bottom)
			)
		)
		(property "Description" " "
			(at 0 0 180)
			(layer "F.Fab")
			(hide yes)
			(effects
				(font
					(size 1.27 1.27)
					(thickness 0.15)
				)
			)
		)
		(property "Author" "Antmicro"
			(at 300.9128 174.6992 0)
			(layer "F.Fab")
			(hide yes)
			(effects
				(font
					(size 1 1)
					(thickness 0.15)
				)
			)
		)
		(property "Dielectric" ""
			(at 300.9128 174.6992 0)
			(layer "F.Fab")
			(hide yes)
			(effects
				(font
					(size 1 1)
					(thickness 0.15)
				)
			)
		)
		(property "License" "Apache-2.0"
			(at 300.9128 174.6992 0)
			(layer "F.Fab")
			(hide yes)
			(effects
				(font
					(size 1 1)
					(thickness 0.15)
				)
			)
		)
		(property "MPN" "T520D337M006ATE045"
			(at 300.9128 174.6992 0)
			(layer "F.Fab")
			(hide yes)
			(effects
				(font
					(size 1 1)
					(thickness 0.15)
				)
			)
		)
		(property "Manufacturer" "KEMET"
			(at 300.9128 174.6992 0)
			(layer "F.Fab")
			(hide yes)
			(effects
				(font
					(size 1 1)
					(thickness 0.15)
				)
			)
		)
		(property "Val" "330u"
			(at 300.9128 174.6992 0)
			(layer "F.Fab")
			(hide yes)
			(effects
				(font
					(size 1 1)
					(thickness 0.15)
				)
			)
		)
		(property "Voltage" ""
			(at 300.9128 174.6992 0)
			(layer "F.Fab")
			(hide yes)
			(effects
				(font
					(size 1 1)
					(thickness 0.15)
				)
			)
		)
		(sheetname "FPGA power")
		(sheetfile "fpga-power.kicad_sch")
		(attr smd)
		(fp_line
			(start 3.65 2.15)
			(end 3.65 1.6)
			(stroke
				(width 0.15)
				(type solid)
			)
			(layer "F.SilkS")
		)
		(fp_line
			(start 3.65 -2.15)
			(end 3.65 -1.6)
			(stroke
				(width 0.15)
				(type solid)
			)
			(layer "F.SilkS")
		)
		(fp_line
			(start -3.65 2.15)
			(end 3.65 2.15)
			(stroke
				(width 0.15)
				(type solid)
			)
			(layer "F.SilkS")
		)
		(fp_line
			(start -3.65 1.6)
			(end -3.65 2.15)
			(stroke
				(width 0.15)
				(type solid)
			)
			(layer "F.SilkS")
		)
		(fp_line
			(start -3.65 -1.6)
			(end -3.65 -2.15)
			(stroke
				(width 0.15)
				(type solid)
			)
			(layer "F.SilkS")
		)
		(fp_line
			(start -3.65 -2.15)
			(end 3.65 -2.15)
			(stroke
				(width 0.15)
				(type solid)
			)
			(layer "F.SilkS")
		)
		(fp_line
			(start -4 -1.75)
			(end -4 -1.35)
			(stroke
				(width 0.12)
				(type solid)
			)
			(layer "F.SilkS")
		)
		(fp_line
			(start -4.2 -1.55)
			(end -3.8 -1.55)
			(stroke
				(width 0.12)
				(type solid)
			)
			(layer "F.SilkS")
		)
		(fp_line
			(start 4.3 1.5)
			(end 3.8 1.5)
			(stroke
				(width 0.05)
				(type solid)
			)
			(layer "F.CrtYd")
		)
		(fp_line
			(start 4.3 -1.5)
			(end 4.3 1.5)
			(stroke
				(width 0.05)
				(type solid)
			)
			(layer "F.CrtYd")
		)
		(fp_line
			(start 3.8 2.4)
			(end -3.8 2.4)
			(stroke
				(width 0.05)
				(type solid)
			)
			(layer "F.CrtYd")
		)
		(fp_line
			(start 3.8 1.5)
			(end 3.8 2.4)
			(stroke
				(width 0.05)
				(type solid)
			)
			(layer "F.CrtYd")
		)
		(fp_line
			(start 3.8 -1.5)
			(end 4.3 -1.5)
			(stroke
				(width 0.05)
				(type solid)
			)
			(layer "F.CrtYd")
		)
		(fp_line
			(start 3.8 -2.4)
			(end 3.8 -1.5)
			(stroke
				(width 0.05)
				(type solid)
			)
			(layer "F.CrtYd")
		)
		(fp_line
			(start -3.8 2.4)
			(end -3.8 1.5)
			(stroke
				(width 0.05)
				(type solid)
			)
			(layer "F.CrtYd")
		)
		(fp_line
			(start -3.8 1.5)
			(end -4.3 1.5)
			(stroke
				(width 0.05)
				(type solid)
			)
			(layer "F.CrtYd")
		)
		(fp_line
			(start -3.8 -1.5)
			(end -4.3 -1.5)
			(stroke
				(width 0.05)
				(type solid)
			)
			(layer "F.CrtYd")
		)
		(fp_line
			(start -3.8 -2.4)
			(end 3.8 -2.4)
			(stroke
				(width 0.05)
				(type solid)
			)
			(layer "F.CrtYd")
		)
		(fp_line
			(start -3.8 -2.4)
			(end -3.8 -1.5)
			(stroke
				(width 0.05)
				(type solid)
			)
			(layer "F.CrtYd")
		)
		(fp_line
			(start -4.3 1.5)
			(end -4.3 -1.5)
			(stroke
				(width 0.05)
				(type solid)
			)
			(layer "F.CrtYd")
		)
		(fp_rect
			(start -3.65 -2.15)
			(end 3.65 2.15)
			(stroke
				(width 0.15)
				(type solid)
			)
			(fill no)
			(layer "F.Fab")
		)
		(pad "1" smd rect
			(at -3.1 0 180)
			(size 2.31 2.52)
			(layers "F.Cu" "F.Mask" "F.Paste")
			(net 465 "1V0_SYS")
			(pintype "passive")
		)
		(pad "2" smd rect
			(at 3.1 0 180)
			(size 2.31 2.52)
			(layers "F.Cu" "F.Mask" "F.Paste")
			(net 5 "GND")
			(pintype "passive")
		)
	)
	(footprint "antmicro-footprints:C_0603_1608Metric"
		(layer "F.Cu")
		(at 151.003 92.455)
		(descr "Capacitor SMD 0603")
		(tags "capacitor 0603")
		(property "Reference" "C1"
			(at -0.779 -0.655 0)
			(layer "F.SilkS")
			(effects
				(font
					(size 0.7 0.7)
					(thickness 0.15)
				)
				(justify left bottom)
			)
		)
		(property "Value" "C_47u_0603"
			(at 0 1.6 0)
			(layer "F.Fab")
			(effects
				(font
					(size 0.7 0.7)
					(thickness 0.15)
				)
				(justify left bottom)
			)
		)
		(property "Description" " "
			(at 0 0 0)
			(layer "F.Fab")
			(hide yes)
			(effects
				(font
					(size 1.27 1.27)
					(thickness 0.15)
				)
			)
		)
		(property "Author" "Antmicro"
			(at 0 0 0)
			(layer "F.Fab")
			(hide yes)
			(effects
				(font
					(size 1 1)
					(thickness 0.15)
				)
			)
		)
		(property "Dielectric" ""
			(at 0 0 0)
			(layer "F.Fab")
			(hide yes)
			(effects
				(font
					(size 1 1)
					(thickness 0.15)
				)
			)
		)
		(property "License" "Apache-2.0"
			(at 0 0 0)
			(layer "F.Fab")
			(hide yes)
			(effects
				(font
					(size 1 1)
					(thickness 0.15)
				)
			)
		)
		(property "MPN" "GRM188R60J476ME15D"
			(at 0 0 0)
			(layer "F.Fab")
			(hide yes)
			(effects
				(font
					(size 1 1)
					(thickness 0.15)
				)
			)
		)
		(property "Manufacturer" "Murata"
			(at 0 0 0)
			(layer "F.Fab")
			(hide yes)
			(effects
				(font
					(size 1 1)
					(thickness 0.15)
				)
			)
		)
		(property "Val" "47u"
			(at 0 0 0)
			(layer "F.Fab")
			(hide yes)
			(effects
				(font
					(size 1 1)
					(thickness 0.15)
				)
			)
		)
		(property "Voltage" ""
			(at 0 0 0)
			(layer "F.Fab")
			(hide yes)
			(effects
				(font
					(size 1 1)
					(thickness 0.15)
				)
			)
		)
		(sheetname "HyperRAM")
		(sheetfile "hyperram.kicad_sch")
		(attr smd)
		(fp_line
			(start -0.3 -0.3)
			(end 0.3 -0.3)
			(stroke
				(width 0.15)
				(type solid)
			)
			(layer "F.SilkS")
		)
		(fp_line
			(start -0.3 0.3)
			(end 0.3 0.3)
			(stroke
				(width 0.15)
				(type solid)
			)
			(layer "F.SilkS")
		)
		(fp_rect
			(start -1.24 -0.7)
			(end 1.24 0.7)
			(stroke
				(width 0.05)
				(type solid)
			)
			(fill no)
			(layer "F.CrtYd")
		)
		(fp_rect
			(start -0.8 -0.4)
			(end 0.8 0.4)
			(stroke
				(width 0.15)
				(type solid)
			)
			(fill no)
			(layer "F.Fab")
		)
		(pad "1" smd roundrect
			(at -0.7 0)
			(size 0.6 0.8)
			(layers "F.Cu" "F.Mask" "F.Paste")
			(roundrect_rratio 0.2)
			(net 459 "3V3_SYS")
			(pintype "passive")
		)
		(pad "2" smd roundrect
			(at 0.7 0)
			(size 0.6 0.8)
			(layers "F.Cu" "F.Mask" "F.Paste")
			(roundrect_rratio 0.2)
			(net 5 "GND")
			(pintype "passive")
		)
	)
	(footprint "antmicro-footprints:R_0402_1005Metric"
		(layer "F.Cu")
		(at 148.9202 92.201 -90)
		(descr "Resistor SMD 0402")
		(tags "resistor SMD 0402")
		(property "Reference" "R1"
			(at -0.701 -0.3974 270)
			(layer "F.SilkS")
			(effects
				(font
					(size 0.7 0.7)
					(thickness 0.15)
				)
				(justify left bottom)
			)
		)
		(property "Value" "R_10k_0402"
			(at 0 1.4 270)
			(layer "F.Fab")
			(effects
				(font
					(size 0.7 0.7)
					(thickness 0.15)
				)
				(justify left bottom)
			)
		)
		(property "Description" "10k resistor in 0402 package with 1% tolerance"
			(at 0 0 270)
			(layer "F.Fab")
			(hide yes)
			(effects
				(font
					(size 1.27 1.27)
					(thickness 0.15)
				)
			)
		)
		(property "Author" "Antmicro"
			(at 56.7192 241.1212 0)
			(layer "F.Fab")
			(hide yes)
			(effects
				(font
					(size 1 1)
					(thickness 0.15)
				)
			)
		)
		(property "License" "Apache-2.0"
			(at 56.7192 241.1212 0)
			(layer "F.Fab")
			(hide yes)
			(effects
				(font
					(size 1 1)
					(thickness 0.15)
				)
			)
		)
		(property "MPN" "CR0402-FX-1002GLF"
			(at 56.7192 241.1212 0)
			(layer "F.Fab")
			(hide yes)
			(effects
				(font
					(size 1 1)
					(thickness 0.15)
				)
			)
		)
		(property "Manufacturer" "Bourns"
			(at 56.7192 241.1212 0)
			(layer "F.Fab")
			(hide yes)
			(effects
				(font
					(size 1 1)
					(thickness 0.15)
				)
			)
		)
		(property "Tolerance" "1%"
			(at 56.7192 241.1212 0)
			(layer "F.Fab")
			(hide yes)
			(effects
				(font
					(size 1 1)
					(thickness 0.15)
				)
			)
		)
		(property "Val" "10k"
			(at 56.7192 241.1212 0)
			(layer "F.Fab")
			(hide yes)
			(effects
				(font
					(size 1 1)
					(thickness 0.15)
				)
			)
		)
		(sheetname "HyperRAM")
		(sheetfile "hyperram.kicad_sch")
		(attr smd)
		(fp_rect
			(start -0.93 -0.47)
			(end 0.93 0.47)
			(stroke
				(width 0.05)
				(type solid)
			)
			(fill no)
			(layer "F.CrtYd")
		)
		(fp_rect
			(start -0.5 -0.25)
			(end 0.5 0.25)
			(stroke
				(width 0.15)
				(type solid)
			)
			(fill no)
			(layer "F.Fab")
		)
		(pad "1" smd roundrect
			(at -0.485 0 270)
			(size 0.59 0.64)
			(layers "F.Cu" "F.Mask" "F.Paste")
			(roundrect_rratio 0.25)
			(net 459 "3V3_SYS")
			(pintype "passive")
		)
		(pad "2" smd roundrect
			(at 0.485 0 270)
			(size 0.59 0.64)
			(layers "F.Cu" "F.Mask" "F.Paste")
			(roundrect_rratio 0.25)
			(net 488 "HR_RST")
			(pintype "passive")
		)
	)
)
